# T6G (Grand Teton) — schematic netlist excerpt (pin names and nets, part order shuffled) for the footprints in the layout excerpt that follows; sources: Cadence DE-HDL packaged netlist, KiCad conversion of 04192023_DAF0TMB3IC0_F0TG_MB_C_brd_V02_OCP.brd

R747  Q_RES  1K 1% CHIP  pkg 0402LF  page 76 : A = GND ; B = UART_CPU0_SCM_UART1_TX
R1032  Q_RES  4.7K 5% EMPTY  pkg 0201LF  page 287 : A = P1V8_CPU0_RT_1D ; B = TEST1_RT_CPU0_P1
C2565  Q_CAP  22UF 4V 20% X6S  pkg C0402  page 70 : A = PVDDCR_SOC_P0 ; B = GND

(kicad_pcb
	(version 20260206)
	(generator "pcbnew")
	(generator_version "10.0")
	(general
		(thickness 1.6)
		(legacy_teardrops no)
	)
	(paper "A4")
	(title_block
		(title "04192023_DAF0TMB3IC0_F0TG_MB_C_brd_V02_OCP.brd")
		(comment 1 "Grand Teton / footprints 8321-8323 of 8354")
	)
	(layers
		(0 "F.Cu" signal "TOP")
		(4 "In1.Cu" signal "GND")
		(6 "In2.Cu" signal "IN1")
		(8 "In3.Cu" signal "GND1")
		(10 "In4.Cu" signal "IN2")
		(12 "In5.Cu" signal "GND2")
		(14 "In6.Cu" signal "IN3")
		(16 "In7.Cu" signal "GND3")
		(18 "In8.Cu" signal "VCC")
		(20 "In9.Cu" signal "VCC1")
		(22 "In10.Cu" signal "GND4")
		(24 "In11.Cu" signal "IN4")
		(26 "In12.Cu" signal "GND5")
		(28 "In13.Cu" signal "IN5")
		(30 "In14.Cu" signal "GND6")
		(32 "In15.Cu" signal "IN6")
		(34 "In16.Cu" signal "GND7")
		(2 "B.Cu" signal "BOTTOM")
		(9 "F.Adhes" user "F.Adhesive")
		(11 "B.Adhes" user "B.Adhesive")
		(13 "F.Paste" user "Package Geometry/Pastemask Top")
		(15 "B.Paste" user "Package Geometry/Pastemask Bottom")
		(5 "F.SilkS" user "Ref Des/Silkscreen Top")
		(7 "B.SilkS" user "Ref Des/Silkscreen Bottom")
		(1 "F.Mask" user "Board Geometry/Soldermask Top")
		(3 "B.Mask" user "Board Geometry/Soldermask Bottom")
		(17 "Dwgs.User" user "User.Drawings")
		(19 "Cmts.User" user "User.Comments")
		(21 "Eco1.User" user "User.Eco1")
		(23 "Eco2.User" user "User.Eco2")
		(25 "Edge.Cuts" user "Board Geometry/Outline")
		(27 "Margin" user)
		(31 "F.CrtYd" user "Package Geometry/Place Bound Top")
		(29 "B.CrtYd" user "Package Geometry/Place Bound Bottom")
		(35 "F.Fab" user "Ref Des/Assembly Top")
		(33 "B.Fab" user "Ref Des/Assembly Bottom")
	)
	(footprint ""
		(layer "B.Cu")
		(at 339.134958 -307.717952 180)
		(property "Reference" "R747"
			(at 0 0 0)
			(layer "B.SilkS")
			(hide yes)
			(effects
				(font
					(size 1.27 1.27)
				)
				(justify mirror)
			)
		)
		(property "Value" ""
			(at 0 0 0)
			(layer "B.Fab")
			(effects
				(font
					(size 1.27 1.27)
				)
				(justify mirror)
			)
		)
		(duplicate_pad_numbers_are_jumpers no)
		(fp_line
			(start 0.7874 0.4064)
			(end 0.7874 -0.4064)
			(stroke
				(width 0.1524)
				(type default)
			)
			(layer "B.SilkS")
		)
		(fp_line
			(start 0.7874 -0.4064)
			(end -0.7874 -0.4064)
			(stroke
				(width 0.1524)
				(type default)
			)
			(layer "B.SilkS")
		)
		(fp_line
			(start -0.7874 0.4064)
			(end 0.7874 0.4064)
			(stroke
				(width 0.1524)
				(type default)
			)
			(layer "B.SilkS")
		)
		(fp_line
			(start -0.7874 -0.4064)
			(end -0.7874 0.4064)
			(stroke
				(width 0.1524)
				(type default)
			)
			(layer "B.SilkS")
		)
		(fp_line
			(start 0.67945 0.3048)
			(end 0.67945 -0.305054)
			(stroke
				(width 0.1)
				(type default)
			)
			(layer "B.Fab")
		)
		(fp_line
			(start 0.67945 -0.305054)
			(end 0.12065 -0.305054)
			(stroke
				(width 0.1)
				(type default)
			)
			(layer "B.Fab")
		)
		(fp_line
			(start 0.12065 0.3048)
			(end 0.67945 0.3048)
			(stroke
				(width 0.1)
				(type default)
			)
			(layer "B.Fab")
		)
		(fp_line
			(start 0.12065 0.2794)
			(end 0.12065 0.3048)
			(stroke
				(width 0.1)
				(type default)
			)
			(layer "B.Fab")
		)
		(fp_line
			(start 0.12065 -0.2794)
			(end -0.12065 -0.2794)
			(stroke
				(width 0.1)
				(type default)
			)
			(layer "B.Fab")
		)
		(fp_line
			(start 0.12065 -0.305054)
			(end 0.12065 -0.2794)
			(stroke
				(width 0.1)
				(type default)
			)
			(layer "B.Fab")
		)
		(fp_line
			(start -0.120396 0.3048)
			(end -0.120396 0.2794)
			(stroke
				(width 0.1)
				(type default)
			)
			(layer "B.Fab")
		)
		(fp_line
			(start -0.120396 0.2794)
			(end 0.12065 0.2794)
			(stroke
				(width 0.1)
				(type default)
			)
			(layer "B.Fab")
		)
		(fp_line
			(start -0.12065 -0.2794)
			(end -0.12065 -0.3048)
			(stroke
				(width 0.1)
				(type default)
			)
			(layer "B.Fab")
		)
		(fp_line
			(start -0.12065 -0.3048)
			(end -0.67945 -0.3048)
			(stroke
				(width 0.1)
				(type default)
			)
			(layer "B.Fab")
		)
		(fp_line
			(start -0.67945 0.3048)
			(end -0.120396 0.3048)
			(stroke
				(width 0.1)
				(type default)
			)
			(layer "B.Fab")
		)
		(fp_line
			(start -0.67945 -0.3048)
			(end -0.67945 0.3048)
			(stroke
				(width 0.1)
				(type default)
			)
			(layer "B.Fab")
		)
		(pad "1" smd circle
			(at 0.40005 0)
			(size 0 0)
			(layers "B.Cu" "B.Mask" "B.Paste")
			(net "GND")
		)
		(pad "2" smd circle
			(at -0.40005 0)
			(size 0 0)
			(layers "B.Cu" "B.Mask" "B.Paste")
			(net "UART_CPU0_SCM_UART1_TX")
		)
	)
	(footprint ""
		(layer "B.Cu")
		(at 363.645958 -257.744976 180)
		(property "Reference" "C2565"
			(at 0 0 0)
			(layer "B.SilkS")
			(hide yes)
			(effects
				(font
					(size 1.27 1.27)
				)
				(justify mirror)
			)
		)
		(property "Value" ""
			(at 0 0 0)
			(layer "B.Fab")
			(effects
				(font
					(size 1.27 1.27)
				)
				(justify mirror)
			)
		)
		(duplicate_pad_numbers_are_jumpers no)
		(fp_line
			(start 0.7874 0.4064)
			(end 0.7874 -0.4064)
			(stroke
				(width 0.1524)
				(type default)
			)
			(layer "B.SilkS")
		)
		(fp_line
			(start 0.7874 -0.4064)
			(end -0.7874 -0.4064)
			(stroke
				(width 0.1524)
				(type default)
			)
			(layer "B.SilkS")
		)
		(fp_line
			(start -0.7874 0.4064)
			(end 0.7874 0.4064)
			(stroke
				(width 0.1524)
				(type default)
			)
			(layer "B.SilkS")
		)
		(fp_line
			(start -0.7874 -0.4064)
			(end -0.7874 0.4064)
			(stroke
				(width 0.1524)
				(type default)
			)
			(layer "B.SilkS")
		)
		(fp_line
			(start 0.67945 0.3048)
			(end 0.67945 -0.305054)
			(stroke
				(width 0.1)
				(type default)
			)
			(layer "B.Fab")
		)
		(fp_line
			(start 0.67945 -0.305054)
			(end 0.12065 -0.305054)
			(stroke
				(width 0.1)
				(type default)
			)
			(layer "B.Fab")
		)
		(fp_line
			(start 0.12065 0.3048)
			(end 0.67945 0.3048)
			(stroke
				(width 0.1)
				(type default)
			)
			(layer "B.Fab")
		)
		(fp_line
			(start 0.12065 0.2794)
			(end 0.12065 0.3048)
			(stroke
				(width 0.1)
				(type default)
			)
			(layer "B.Fab")
		)
		(fp_line
			(start 0.12065 -0.2794)
			(end -0.12065 -0.2794)
			(stroke
				(width 0.1)
				(type default)
			)
			(layer "B.Fab")
		)
		(fp_line
			(start 0.12065 -0.305054)
			(end 0.12065 -0.2794)
			(stroke
				(width 0.1)
				(type default)
			)
			(layer "B.Fab")
		)
		(fp_line
			(start -0.120396 0.3048)
			(end -0.120396 0.2794)
			(stroke
				(width 0.1)
				(type default)
			)
			(layer "B.Fab")
		)
		(fp_line
			(start -0.120396 0.2794)
			(end 0.12065 0.2794)
			(stroke
				(width 0.1)
				(type default)
			)
			(layer "B.Fab")
		)
		(fp_line
			(start -0.12065 -0.2794)
			(end -0.12065 -0.3048)
			(stroke
				(width 0.1)
				(type default)
			)
			(layer "B.Fab")
		)
		(fp_line
			(start -0.12065 -0.3048)
			(end -0.67945 -0.3048)
			(stroke
				(width 0.1)
				(type default)
			)
			(layer "B.Fab")
		)
		(fp_line
			(start -0.67945 0.3048)
			(end -0.120396 0.3048)
			(stroke
				(width 0.1)
				(type default)
			)
			(layer "B.Fab")
		)
		(fp_line
			(start -0.67945 -0.3048)
			(end -0.67945 0.3048)
			(stroke
				(width 0.1)
				(type default)
			)
			(layer "B.Fab")
		)
		(pad "1" smd circle
			(at 0.40005 0)
			(size 0 0)
			(layers "B.Cu" "B.Mask" "B.Paste")
			(net "PVDDCR_SOC_P0")
		)
		(pad "2" smd circle
			(at -0.40005 0)
			(size 0 0)
			(layers "B.Cu" "B.Mask" "B.Paste")
			(net "GND")
		)
	)
	(footprint ""
		(layer "B.Cu")
		(at 330.523342 -393.04468 180)
		(property "Reference" "R1032"
			(at 0 0 0)
			(layer "B.SilkS")
			(hide yes)
			(effects
				(font
					(size 1.27 1.27)
				)
				(justify mirror)
			)
		)
		(property "Value" ""
			(at 0 0 0)
			(layer "B.Fab")
			(effects
				(font
					(size 1.27 1.27)
				)
				(justify mirror)
			)
		)
		(duplicate_pad_numbers_are_jumpers no)
		(fp_line
			(start 0.32512 0.175006)
			(end 0.32512 -0.175006)
			(stroke
				(width 0.1)
				(type default)
			)
			(layer "B.Fab")
		)
		(fp_line
			(start 0.32512 -0.175006)
			(end -0.32512 -0.175006)
			(stroke
				(width 0.1)
				(type default)
			)
			(layer "B.Fab")
		)
		(fp_line
			(start -0.32512 0.175006)
			(end 0.32512 0.175006)
			(stroke
				(width 0.1)
				(type default)
			)
			(layer "B.Fab")
		)
		(fp_line
			(start -0.32512 -0.175006)
			(end -0.32512 0.175006)
			(stroke
				(width 0.1)
				(type default)
			)
			(layer "B.Fab")
		)
		(pad "1" smd rect
			(at 0.2667 0)
			(size 0.3048 0.381)
			(layers "B.Cu" "B.Mask" "B.Paste")
			(net "P1V8_CPU0_RT_1D")
		)
		(pad "2" smd rect
			(at -0.2667 0 180)
			(size 0.3048 0.381)
			(layers "B.Cu" "B.Mask" "B.Paste")
			(net "TEST1_RT_CPU0_P1")
		)
	)
)
